# S9S_MB_2U (Grand Teton) — schematic netlist excerpt (pin names and nets, part order shuffled) for the footprints in the layout excerpt that follows; sources: Cadence DE-HDL packaged netlist, KiCad conversion of 03242023_DA0F0TMBIJ0_F0T_Motherboard_J_brd_V01_OCP.brd

C460  Q_CAP  47UF 4V 20% X6S  pkg C0805  page 79 : A = PVCCFA_EHV_CPU1 ; B = GND
R151  Q_RES  100 1% CHIP  pkg 0402LF  page 125 : A = PWRGD_DRAMPWRGD_CPU1_EF_LVC1_R2 ; B = PVCCD_HV_CPU1
R12  Q_RES  0 5% CHIP  pkg 0402LF  page 14 : A = SVID_DIO0_CPU0 ; B = SVID_DIO0_CPU0_R

(kicad_pcb
	(version 20260206)
	(generator "pcbnew")
	(generator_version "10.0")
	(general
		(thickness 1.6)
		(legacy_teardrops no)
	)
	(paper "A4")
	(title_block
		(title "03242023_DA0F0TMBIJ0_F0T_Motherboard_J_brd_V01_OCP.brd")
		(comment 1 "Grand Teton / footprints 5920-5922 of 6105")
	)
	(layers
		(0 "F.Cu" signal "TOP")
		(4 "In1.Cu" signal "GND")
		(6 "In2.Cu" signal "IN1")
		(8 "In3.Cu" signal "GND1")
		(10 "In4.Cu" signal "IN2")
		(12 "In5.Cu" signal "GND2")
		(14 "In6.Cu" signal "IN3")
		(16 "In7.Cu" signal "GND3")
		(18 "In8.Cu" signal "VCC")
		(20 "In9.Cu" signal "VCC1")
		(22 "In10.Cu" signal "GND4")
		(24 "In11.Cu" signal "IN4")
		(26 "In12.Cu" signal "GND5")
		(28 "In13.Cu" signal "IN5")
		(30 "In14.Cu" signal "GND6")
		(32 "In15.Cu" signal "IN6")
		(34 "In16.Cu" signal "GND7")
		(2 "B.Cu" signal "BOTTOM")
		(9 "F.Adhes" user "F.Adhesive")
		(11 "B.Adhes" user "B.Adhesive")
		(13 "F.Paste" user "Package Geometry/Pastemask Top")
		(15 "B.Paste" user "Package Geometry/Pastemask Bottom")
		(5 "F.SilkS" user "Ref Des/Silkscreen Top")
		(7 "B.SilkS" user "Ref Des/Silkscreen Bottom")
		(1 "F.Mask" user "Board Geometry/Soldermask Top")
		(3 "B.Mask" user "Board Geometry/Soldermask Bottom")
		(17 "Dwgs.User" user "User.Drawings")
		(19 "Cmts.User" user "User.Comments")
		(21 "Eco1.User" user "User.Eco1")
		(23 "Eco2.User" user "User.Eco2")
		(25 "Edge.Cuts" user "Board Geometry/Outline")
		(27 "Margin" user)
		(31 "F.CrtYd" user "Package Geometry/Place Bound Top")
		(29 "B.CrtYd" user "Package Geometry/Place Bound Bottom")
		(35 "F.Fab" user "Ref Des/Assembly Top")
		(33 "B.Fab" user "Ref Des/Assembly Bottom")
	)
	(footprint ""
		(layer "B.Cu")
		(at 169.506138 -193.01079 90)
		(property "Reference" "R151"
			(at 0 0 90)
			(layer "B.SilkS")
			(hide yes)
			(effects
				(font
					(size 1.27 1.27)
				)
				(justify mirror)
			)
		)
		(property "Value" ""
			(at 0 0 90)
			(layer "B.Fab")
			(effects
				(font
					(size 1.27 1.27)
				)
				(justify mirror)
			)
		)
		(duplicate_pad_numbers_are_jumpers no)
		(fp_line
			(start 0.7874 -0.4064)
			(end -0.7874 -0.4064)
			(stroke
				(width 0.1524)
				(type default)
			)
			(layer "B.SilkS")
		)
		(fp_line
			(start -0.7874 -0.4064)
			(end -0.7874 0.4064)
			(stroke
				(width 0.1524)
				(type default)
			)
			(layer "B.SilkS")
		)
		(fp_line
			(start 0.7874 0.4064)
			(end 0.7874 -0.4064)
			(stroke
				(width 0.1524)
				(type default)
			)
			(layer "B.SilkS")
		)
		(fp_line
			(start -0.7874 0.4064)
			(end 0.7874 0.4064)
			(stroke
				(width 0.1524)
				(type default)
			)
			(layer "B.SilkS")
		)
		(fp_line
			(start 0.67945 -0.305054)
			(end 0.12065 -0.305054)
			(stroke
				(width 0.1)
				(type default)
			)
			(layer "B.Fab")
		)
		(fp_line
			(start 0.12065 -0.305054)
			(end 0.12065 -0.2794)
			(stroke
				(width 0.1)
				(type default)
			)
			(layer "B.Fab")
		)
		(fp_line
			(start -0.12065 -0.3048)
			(end -0.67945 -0.3048)
			(stroke
				(width 0.1)
				(type default)
			)
			(layer "B.Fab")
		)
		(fp_line
			(start -0.67945 -0.3048)
			(end -0.67945 0.3048)
			(stroke
				(width 0.1)
				(type default)
			)
			(layer "B.Fab")
		)
		(fp_line
			(start 0.12065 -0.2794)
			(end -0.12065 -0.2794)
			(stroke
				(width 0.1)
				(type default)
			)
			(layer "B.Fab")
		)
		(fp_line
			(start -0.12065 -0.2794)
			(end -0.12065 -0.3048)
			(stroke
				(width 0.1)
				(type default)
			)
			(layer "B.Fab")
		)
		(fp_line
			(start 0.12065 0.2794)
			(end 0.12065 0.3048)
			(stroke
				(width 0.1)
				(type default)
			)
			(layer "B.Fab")
		)
		(fp_line
			(start -0.120396 0.2794)
			(end 0.12065 0.2794)
			(stroke
				(width 0.1)
				(type default)
			)
			(layer "B.Fab")
		)
		(fp_line
			(start 0.67945 0.3048)
			(end 0.67945 -0.305054)
			(stroke
				(width 0.1)
				(type default)
			)
			(layer "B.Fab")
		)
		(fp_line
			(start 0.12065 0.3048)
			(end 0.67945 0.3048)
			(stroke
				(width 0.1)
				(type default)
			)
			(layer "B.Fab")
		)
		(fp_line
			(start -0.120396 0.3048)
			(end -0.120396 0.2794)
			(stroke
				(width 0.1)
				(type default)
			)
			(layer "B.Fab")
		)
		(fp_line
			(start -0.67945 0.3048)
			(end -0.120396 0.3048)
			(stroke
				(width 0.1)
				(type default)
			)
			(layer "B.Fab")
		)
		(pad "1" smd circle
			(at 0.40005 0 270)
			(size 0 0)
			(layers "B.Cu" "B.Mask" "B.Paste")
			(net "PWRGD_DRAMPWRGD_CPU1_EF_LVC1_R2")
		)
		(pad "2" smd circle
			(at -0.40005 0 270)
			(size 0 0)
			(layers "B.Cu" "B.Mask" "B.Paste")
			(net "PVCCD_HV_CPU1")
		)
	)
	(footprint ""
		(layer "B.Cu")
		(at 107.887008 -212.049868 180)
		(property "Reference" "C460"
			(at 0 0 0)
			(layer "B.SilkS")
			(hide yes)
			(effects
				(font
					(size 1.27 1.27)
				)
				(justify mirror)
			)
		)
		(property "Value" ""
			(at 0 0 0)
			(layer "B.Fab")
			(effects
				(font
					(size 1.27 1.27)
				)
				(justify mirror)
			)
		)
		(duplicate_pad_numbers_are_jumpers no)
		(fp_line
			(start 1.524 0.762)
			(end 1.524 -0.762)
			(stroke
				(width 0.1524)
				(type default)
			)
			(layer "B.SilkS")
		)
		(fp_line
			(start 1.524 -0.762)
			(end -1.524 -0.762)
			(stroke
				(width 0.1524)
				(type default)
			)
			(layer "B.SilkS")
		)
		(fp_line
			(start -1.524 0.762)
			(end 1.524 0.762)
			(stroke
				(width 0.1524)
				(type default)
			)
			(layer "B.SilkS")
		)
		(fp_line
			(start -1.524 -0.762)
			(end -1.524 0.762)
			(stroke
				(width 0.1524)
				(type default)
			)
			(layer "B.SilkS")
		)
		(fp_line
			(start 1.1049 0.724916)
			(end -1.1049 0.724916)
			(stroke
				(width 0.1)
				(type default)
			)
			(layer "B.Fab")
		)
		(fp_line
			(start 1.1049 -0.724916)
			(end 1.1049 0.724916)
			(stroke
				(width 0.1)
				(type default)
			)
			(layer "B.Fab")
		)
		(fp_line
			(start -1.1049 0.724916)
			(end -1.1049 -0.724916)
			(stroke
				(width 0.1)
				(type default)
			)
			(layer "B.Fab")
		)
		(fp_line
			(start -1.1049 -0.724916)
			(end 1.1049 -0.724916)
			(stroke
				(width 0.1)
				(type default)
			)
			(layer "B.Fab")
		)
		(pad "1" smd rect
			(at 0.889 0 180)
			(size 1.016 1.27)
			(layers "B.Cu" "B.Mask" "B.Paste")
			(net "PVCCFA_EHV_CPU1")
		)
		(pad "2" smd rect
			(at -0.889 0 180)
			(size 1.016 1.27)
			(layers "B.Cu" "B.Mask" "B.Paste")
			(net "GND")
		)
	)
	(footprint ""
		(layer "B.Cu")
		(at 304.926238 -194.72021 90)
		(property "Reference" "R12"
			(at 0 0 90)
			(layer "B.SilkS")
			(hide yes)
			(effects
				(font
					(size 1.27 1.27)
				)
				(justify mirror)
			)
		)
		(property "Value" ""
			(at 0 0 90)
			(layer "B.Fab")
			(effects
				(font
					(size 1.27 1.27)
				)
				(justify mirror)
			)
		)
		(duplicate_pad_numbers_are_jumpers no)
		(fp_line
			(start 0.7874 -0.4064)
			(end -0.7874 -0.4064)
			(stroke
				(width 0.1524)
				(type default)
			)
			(layer "B.SilkS")
		)
		(fp_line
			(start -0.7874 -0.4064)
			(end -0.7874 0.4064)
			(stroke
				(width 0.1524)
				(type default)
			)
			(layer "B.SilkS")
		)
		(fp_line
			(start 0.7874 0.4064)
			(end 0.7874 -0.4064)
			(stroke
				(width 0.1524)
				(type default)
			)
			(layer "B.SilkS")
		)
		(fp_line
			(start -0.7874 0.4064)
			(end 0.7874 0.4064)
			(stroke
				(width 0.1524)
				(type default)
			)
			(layer "B.SilkS")
		)
		(fp_line
			(start 0.67945 -0.305054)
			(end 0.12065 -0.305054)
			(stroke
				(width 0.1)
				(type default)
			)
			(layer "B.Fab")
		)
		(fp_line
			(start 0.12065 -0.305054)
			(end 0.12065 -0.2794)
			(stroke
				(width 0.1)
				(type default)
			)
			(layer "B.Fab")
		)
		(fp_line
			(start -0.12065 -0.3048)
			(end -0.67945 -0.3048)
			(stroke
				(width 0.1)
				(type default)
			)
			(layer "B.Fab")
		)
		(fp_line
			(start -0.67945 -0.3048)
			(end -0.67945 0.3048)
			(stroke
				(width 0.1)
				(type default)
			)
			(layer "B.Fab")
		)
		(fp_line
			(start 0.12065 -0.2794)
			(end -0.12065 -0.2794)
			(stroke
				(width 0.1)
				(type default)
			)
			(layer "B.Fab")
		)
		(fp_line
			(start -0.12065 -0.2794)
			(end -0.12065 -0.3048)
			(stroke
				(width 0.1)
				(type default)
			)
			(layer "B.Fab")
		)
		(fp_line
			(start 0.12065 0.2794)
			(end 0.12065 0.3048)
			(stroke
				(width 0.1)
				(type default)
			)
			(layer "B.Fab")
		)
		(fp_line
			(start -0.120396 0.2794)
			(end 0.12065 0.2794)
			(stroke
				(width 0.1)
				(type default)
			)
			(layer "B.Fab")
		)
		(fp_line
			(start 0.67945 0.3048)
			(end 0.67945 -0.305054)
			(stroke
				(width 0.1)
				(type default)
			)
			(layer "B.Fab")
		)
		(fp_line
			(start 0.12065 0.3048)
			(end 0.67945 0.3048)
			(stroke
				(width 0.1)
				(type default)
			)
			(layer "B.Fab")
		)
		(fp_line
			(start -0.120396 0.3048)
			(end -0.120396 0.2794)
			(stroke
				(width 0.1)
				(type default)
			)
			(layer "B.Fab")
		)
		(fp_line
			(start -0.67945 0.3048)
			(end -0.120396 0.3048)
			(stroke
				(width 0.1)
				(type default)
			)
			(layer "B.Fab")
		)
		(pad "1" smd circle
			(at 0.40005 0 270)
			(size 0 0)
			(layers "B.Cu" "B.Mask" "B.Paste")
			(net "SVID_DIO0_CPU0")
		)
		(pad "2" smd circle
			(at -0.40005 0 270)
			(size 0 0)
			(layers "B.Cu" "B.Mask" "B.Paste")
			(net "SVID_DIO0_CPU0_R")
		)
	)
)
